(kicad_pcb
	(version 20260206)
	(generator "pcbnew")
	(generator_version "10.0")
	(general
		(thickness 1.6)
		(legacy_teardrops no)
	)
	(paper "A4")
	(title_block
		(title "dpb — 14545-sa.0730WZS0815.brd")
		(comment 1 "Honey Badger (Wiwynn) / footprints 332-338 of 1066")
	)
	(layers
		(0 "F.Cu" signal "TOP")
		(4 "In1.Cu" signal "L2GND")
		(6 "In2.Cu" signal "L3")
		(8 "In3.Cu" signal "L4VCC")
		(10 "In4.Cu" signal "L5VCC")
		(12 "In5.Cu" signal "L6")
		(14 "In6.Cu" signal "L7GND")
		(2 "B.Cu" signal "BOTTOM")
		(9 "F.Adhes" user "F.Adhesive")
		(11 "B.Adhes" user "B.Adhesive")
		(13 "F.Paste" user "Package Geometry/Pastemask Top")
		(15 "B.Paste" user "Package Geometry/Pastemask Bottom")
		(5 "F.SilkS" user "Ref Des/Silkscreen Top")
		(7 "B.SilkS" user "Ref Des/Silkscreen Bottom")
		(1 "F.Mask" user "Board Geometry/Soldermask Top")
		(3 "B.Mask" user "Board Geometry/Soldermask Bottom")
		(17 "Dwgs.User" user "User.Drawings")
		(19 "Cmts.User" user "User.Comments")
		(21 "Eco1.User" user "User.Eco1")
		(23 "Eco2.User" user "User.Eco2")
		(25 "Edge.Cuts" user "Board Geometry/Outline")
		(27 "Margin" user)
		(31 "F.CrtYd" user "Package Geometry/Place Bound Top")
		(29 "B.CrtYd" user "Package Geometry/Place Bound Bottom")
		(35 "F.Fab" user "Ref Des/Assembly Top")
		(33 "B.Fab" user "Ref Des/Assembly Bottom")
	)
	(footprint ""
		(layer "F.Cu")
		(at 210.609942 -46.999906 180)
		(property "Reference" "U49"
			(at 0 0 180)
			(layer "F.SilkS")
			(hide yes)
			(effects
				(font
					(size 1.27 1.27)
				)
			)
		)
		(property "Value" "TMP75AIDGKR-GP"
			(at -0.1143 -9.1948 180)
			(unlocked yes)
			(layer "F.Fab")
			(hide yes)
			(effects
				(font
					(size 1.016 1.016)
					(thickness 0.1524)
				)
			)
		)
		(property "Device Type" "MSOP8-1H44"
			(at -0.1143 -10.795 180)
			(unlocked yes)
			(layer "F.Fab")
			(hide yes)
			(effects
				(font
					(size 1.016 1.016)
					(thickness 0.1524)
				)
			)
		)
		(duplicate_pad_numbers_are_jumpers no)
		(fp_line
			(start 1.0795 1.016)
			(end 1.0795 -1.016)
			(stroke
				(width 0.1524)
				(type default)
			)
			(layer "F.SilkS")
		)
		(fp_line
			(start 1.0795 -1.016)
			(end -1.9558 -1.016)
			(stroke
				(width 0.1524)
				(type default)
			)
			(layer "F.SilkS")
		)
		(fp_line
			(start -1.4478 -0.0381)
			(end -1.9558 0.4699)
			(stroke
				(width 0.1524)
				(type default)
			)
			(layer "F.SilkS")
		)
		(fp_line
			(start -1.778 1.0922)
			(end -1.778 3.048)
			(stroke
				(width 0.508)
				(type default)
			)
			(layer "F.SilkS")
		)
		(fp_line
			(start -1.9558 1.016)
			(end 1.0795 1.016)
			(stroke
				(width 0.1524)
				(type default)
			)
			(layer "F.SilkS")
		)
		(fp_line
			(start -1.9558 -0.5461)
			(end -1.4478 -0.0381)
			(stroke
				(width 0.1524)
				(type default)
			)
			(layer "F.SilkS")
		)
		(fp_line
			(start -1.9558 -1.016)
			(end -1.9558 1.016)
			(stroke
				(width 0.1524)
				(type default)
			)
			(layer "F.SilkS")
		)
		(fp_poly
			(pts
				(xy -1.1557 -1.016) (xy -1.1557 1.016) (xy 1.1557 1.016) (xy 1.1557 -1.016)
			)
			(stroke
				(width 0)
				(type default)
			)
			(fill yes)
			(layer "F.SilkS")
		)
		(fp_rect
			(start -1.4986 2.4511)
			(end 1.4986 -2.4511)
			(stroke
				(width 0)
				(type default)
			)
			(fill no)
			(layer "F.CrtYd")
		)
		(fp_poly
			(pts
				(xy -2.032 3.302) (xy -2.032 -3.302) (xy 2.032 -3.302) (xy 2.032 -2.1209) (xy 1.4986 -2.1209) (xy 1.4986 -2.4511)
				(xy -1.4986 -2.4511) (xy -1.4986 2.4511) (xy 1.4986 2.4511) (xy 1.4986 -2.1082) (xy 2.032 -2.1082)
				(xy 2.032 3.302)
			)
			(stroke
				(width 0)
				(type default)
			)
			(fill no)
			(layer "F.CrtYd")
		)
		(fp_rect
			(start -2.032 3.302)
			(end 2.032 -3.302)
			(stroke
				(width 0)
				(type default)
			)
			(fill no)
			(layer "F.Fab")
		)
		(pad "1" smd rect
			(at -0.97536 2.05486 180)
			(size 0.3556 1.524)
			(layers "F.Cu" "F.Mask" "F.Paste")
			(net "TMP4_SDA")
		)
		(pad "2" smd rect
			(at -0.32512 2.05486 180)
			(size 0.3556 1.524)
			(layers "F.Cu" "F.Mask" "F.Paste")
			(net "TMP4_SCL")
		)
		(pad "3" smd rect
			(at 0.32512 2.05486 180)
			(size 0.3556 1.524)
			(layers "F.Cu" "F.Mask" "F.Paste")
			(net "I2C_B_TMP4_ALERT")
		)
		(pad "4" smd rect
			(at 0.97536 2.05486 180)
			(size 0.3556 1.524)
			(layers "F.Cu" "F.Mask" "F.Paste")
			(net "GND")
		)
		(pad "5" smd rect
			(at 0.97536 -2.05486 180)
			(size 0.3556 1.524)
			(layers "F.Cu" "F.Mask" "F.Paste")
			(net "I2C_B_TMP4_A2")
		)
		(pad "6" smd rect
			(at 0.32512 -2.05486 180)
			(size 0.3556 1.524)
			(layers "F.Cu" "F.Mask" "F.Paste")
			(net "I2C_B_TMP4_A1")
		)
		(pad "7" smd rect
			(at -0.32512 -2.05486 180)
			(size 0.3556 1.524)
			(layers "F.Cu" "F.Mask" "F.Paste")
			(net "I2C_B_TMP4_A0")
		)
		(pad "8" smd rect
			(at -0.97536 -2.05486 180)
			(size 0.3556 1.524)
			(layers "F.Cu" "F.Mask" "F.Paste")
			(net "P3V3")
		)
	)
	(footprint ""
		(layer "F.Cu")
		(at 212.5726 -376.6312 180)
		(property "Reference" "Q50"
			(at 0 0 180)
			(layer "F.SilkS")
			(hide yes)
			(effects
				(font
					(size 1.27 1.27)
				)
			)
		)
		(property "Value" "2N7002-11-GP"
			(at 0.127 -8.9662 180)
			(unlocked yes)
			(layer "F.Fab")
			(hide yes)
			(effects
				(font
					(size 1.016 1.016)
					(thickness 0.1524)
				)
			)
		)
		(property "Device Type" "SOT23DGS2D4H44"
			(at 0.127 -10.4902 180)
			(unlocked yes)
			(layer "F.Fab")
			(hide yes)
			(effects
				(font
					(size 1.016 1.016)
					(thickness 0.1524)
				)
			)
		)
		(duplicate_pad_numbers_are_jumpers no)
		(fp_line
			(start 1.651 1.778)
			(end 1.651 -1.778)
			(stroke
				(width 0.1524)
				(type default)
			)
			(layer "F.SilkS")
		)
		(fp_line
			(start 1.651 -1.778)
			(end -1.651 -1.778)
			(stroke
				(width 0.1524)
				(type default)
			)
			(layer "F.SilkS")
		)
		(fp_line
			(start -1.651 1.778)
			(end 1.651 1.778)
			(stroke
				(width 0.1524)
				(type default)
			)
			(layer "F.SilkS")
		)
		(fp_line
			(start -1.651 -1.778)
			(end -1.651 1.778)
			(stroke
				(width 0.1524)
				(type default)
			)
			(layer "F.SilkS")
		)
		(fp_poly
			(pts
				(xy -1.778 1.8796) (xy -1.778 -1.8796) (xy 1.778 -1.8796) (xy 1.778 1.8796)
			)
			(stroke
				(width 0)
				(type default)
			)
			(fill no)
			(layer "F.CrtYd")
		)
		(fp_poly
			(pts
				(xy -1.778 1.8796) (xy -1.778 -1.8796) (xy 1.778 -1.8796) (xy 1.778 1.8796)
			)
			(stroke
				(width 0)
				(type default)
			)
			(fill no)
			(layer "F.Fab")
		)
		(pad "D" smd custom
			(at 0 -0.9525 180)
			(size 0.1905 0.1905)
			(layers "F.Cu" "F.Mask" "F.Paste")
			(net "HDD1_LED_G")
			(options
				(clearance outline)
				(anchor circle)
			)
			(primitives
				(gr_poly
					(pts
						(arc
							(start -0.1778 0.5715)
							(mid -0.321484 0.511984)
							(end -0.381 0.3683)
						)
						(arc
							(start -0.381 -0.3683)
							(mid -0.321484 -0.511984)
							(end -0.1778 -0.5715)
						)
						(arc
							(start 0.1778 -0.5715)
							(mid 0.321484 -0.511984)
							(end 0.381 -0.3683)
						)
						(arc
							(start 0.381 0.3683)
							(mid 0.321484 0.511984)
							(end 0.1778 0.5715)
						)
					)
					(width 0)
					(fill yes)
				)
			)
		)
		(pad "G" smd custom
			(at -0.98425 0.9525 180)
			(size 0.1905 0.1905)
			(layers "F.Cu" "F.Mask" "F.Paste")
			(net "HDD1_LED_B")
			(options
				(clearance outline)
				(anchor circle)
			)
			(primitives
				(gr_poly
					(pts
						(arc
							(start -0.1778 0.5715)
							(mid -0.321484 0.511984)
							(end -0.381 0.3683)
						)
						(arc
							(start -0.381 -0.3683)
							(mid -0.321484 -0.511984)
							(end -0.1778 -0.5715)
						)
						(arc
							(start 0.1778 -0.5715)
							(mid 0.321484 -0.511984)
							(end 0.381 -0.3683)
						)
						(arc
							(start 0.381 0.3683)
							(mid 0.321484 0.511984)
							(end 0.1778 0.5715)
						)
					)
					(width 0)
					(fill yes)
				)
			)
		)
		(pad "S" smd custom
			(at 0.98425 0.9525 180)
			(size 0.1905 0.1905)
			(layers "F.Cu" "F.Mask" "F.Paste")
			(net "GND")
			(options
				(clearance outline)
				(anchor circle)
			)
			(primitives
				(gr_poly
					(pts
						(arc
							(start -0.1778 0.5715)
							(mid -0.321484 0.511984)
							(end -0.381 0.3683)
						)
						(arc
							(start -0.381 -0.3683)
							(mid -0.321484 -0.511984)
							(end -0.1778 -0.5715)
						)
						(arc
							(start 0.1778 -0.5715)
							(mid 0.321484 -0.511984)
							(end 0.381 -0.3683)
						)
						(arc
							(start 0.381 0.3683)
							(mid 0.321484 0.511984)
							(end 0.1778 0.5715)
						)
					)
					(width 0)
					(fill yes)
				)
			)
		)
	)
	(footprint ""
		(layer "F.Cu")
		(at 29.463746 -421.541702 90)
		(property "Reference" "R250"
			(at 0 0 90)
			(layer "F.SilkS")
			(hide yes)
			(effects
				(font
					(size 1.27 1.27)
				)
			)
		)
		(property "Value" "2R2010J-1-GP"
			(at 0.254 -8.0772 90)
			(unlocked yes)
			(layer "F.Fab")
			(hide yes)
			(effects
				(font
					(size 1.016 1.016)
					(thickness 0.1524)
				)
			)
		)
		(property "Device Type" "R2010H28"
			(at 0.254 -9.6774 90)
			(unlocked yes)
			(layer "F.Fab")
			(hide yes)
			(effects
				(font
					(size 1.016 1.016)
					(thickness 0.1524)
				)
			)
		)
		(duplicate_pad_numbers_are_jumpers no)
		(fp_line
			(start 1.651 -3.302)
			(end -1.651 -3.302)
			(stroke
				(width 0.1524)
				(type default)
			)
			(layer "F.SilkS")
		)
		(fp_line
			(start -1.651 -3.302)
			(end -1.651 3.302)
			(stroke
				(width 0.1524)
				(type default)
			)
			(layer "F.SilkS")
		)
		(fp_line
			(start 1.651 3.302)
			(end 1.651 -3.302)
			(stroke
				(width 0.1524)
				(type default)
			)
			(layer "F.SilkS")
		)
		(fp_line
			(start -1.651 3.302)
			(end 1.651 3.302)
			(stroke
				(width 0.1524)
				(type default)
			)
			(layer "F.SilkS")
		)
		(fp_rect
			(start -1.7272 -3.3782)
			(end 1.7272 3.3782)
			(stroke
				(width 0)
				(type default)
			)
			(fill no)
			(layer "F.CrtYd")
		)
		(fp_poly
			(pts
				(xy 1.7272 3.3782) (xy 1.7272 -3.3782) (xy -1.7272 -3.3782) (xy -1.7272 3.3782)
			)
			(stroke
				(width 0)
				(type default)
			)
			(fill no)
			(layer "F.Fab")
		)
		(pad "1" smd rect
			(at 0 -2.3495 90)
			(size 2.794 1.143)
			(layers "F.Cu" "F.Mask" "F.Paste")
			(net "12V_PRE_10")
		)
		(pad "2" smd rect
			(at 0 2.3495 90)
			(size 2.794 1.143)
			(layers "F.Cu" "F.Mask" "F.Paste")
			(net "P12V_HDD10")
		)
	)
	(footprint ""
		(layer "F.Cu")
		(at 30.606746 -314.734702)
		(property "Reference" "C289"
			(at 0 0 0)
			(layer "F.SilkS")
			(hide yes)
			(effects
				(font
					(size 1.27 1.27)
				)
			)
		)
		(property "Value" "SC10U25V6KX-1GP"
			(at -0.0762 -5.1308 0)
			(unlocked yes)
			(layer "F.Fab")
			(hide yes)
			(effects
				(font
					(size 1.016 1.016)
					(thickness 0.1524)
				)
			)
		)
		(property "Device Type" "C1206H71"
			(at -0.127 -6.6548 0)
			(unlocked yes)
			(layer "F.Fab")
			(hide yes)
			(effects
				(font
					(size 1.016 1.016)
					(thickness 0.1524)
				)
			)
		)
		(duplicate_pad_numbers_are_jumpers no)
		(fp_line
			(start -1.016 -2.2352)
			(end 1.016 -2.2352)
			(stroke
				(width 0.1524)
				(type default)
			)
			(layer "F.SilkS")
		)
		(fp_line
			(start -1.016 -0.8382)
			(end -1.016 -2.2352)
			(stroke
				(width 0.1524)
				(type default)
			)
			(layer "F.SilkS")
		)
		(fp_line
			(start -1.016 2.2352)
			(end -1.016 0.8382)
			(stroke
				(width 0.1524)
				(type default)
			)
			(layer "F.SilkS")
		)
		(fp_line
			(start 1.016 -2.2352)
			(end 1.016 -0.8382)
			(stroke
				(width 0.1524)
				(type default)
			)
			(layer "F.SilkS")
		)
		(fp_line
			(start 1.016 0.8382)
			(end 1.016 2.2352)
			(stroke
				(width 0.1524)
				(type default)
			)
			(layer "F.SilkS")
		)
		(fp_line
			(start 1.016 2.2352)
			(end -1.016 2.2352)
			(stroke
				(width 0.1524)
				(type default)
			)
			(layer "F.SilkS")
		)
		(fp_rect
			(start -1.0922 2.3114)
			(end 1.0922 -2.3114)
			(stroke
				(width 0)
				(type default)
			)
			(fill no)
			(layer "F.CrtYd")
		)
		(fp_poly
			(pts
				(xy 1.0922 -2.3114) (xy 1.0922 2.3114) (xy -1.0922 2.3114) (xy -1.0922 -2.3114)
			)
			(stroke
				(width 0)
				(type default)
			)
			(fill no)
			(layer "F.Fab")
		)
		(pad "1" smd rect
			(at 0 -1.397)
			(size 1.651 1.27)
			(layers "F.Cu" "F.Mask" "F.Paste")
			(net "P12V_HDD11")
		)
		(pad "2" smd rect
			(at 0 1.397)
			(size 1.651 1.27)
			(layers "F.Cu" "F.Mask" "F.Paste")
			(net "GND")
		)
	)
	(footprint ""
		(layer "F.Cu")
		(at 218.053412 -70.973696)
		(property "Reference" "C178"
			(at 0 0 0)
			(layer "F.SilkS")
			(hide yes)
			(effects
				(font
					(size 1.27 1.27)
				)
			)
		)
		(property "Value" "SCD01U50V2KX-1GP"
			(at 1.1811 -2.7051 0)
			(unlocked yes)
			(layer "F.Fab")
			(hide yes)
			(effects
				(font
					(size 1.016 1.016)
					(thickness 0.1524)
				)
			)
		)
		(property "Device Type" "C402H22"
			(at 1.1811 -4.2291 0)
			(unlocked yes)
			(layer "F.Fab")
			(hide yes)
			(effects
				(font
					(size 1.016 1.016)
					(thickness 0.1524)
				)
			)
		)
		(duplicate_pad_numbers_are_jumpers no)
		(fp_rect
			(start -0.4318 0.9525)
			(end 0.4318 -0.9525)
			(stroke
				(width 0)
				(type default)
			)
			(fill no)
			(layer "F.CrtYd")
		)
		(fp_rect
			(start -0.4318 0.9525)
			(end 0.4318 -0.9525)
			(stroke
				(width 0)
				(type default)
			)
			(fill no)
			(layer "F.Fab")
		)
		(pad "1" smd custom
			(at 0 -0.4445)
			(size 0.1524 0.1524)
			(layers "F.Cu" "F.Mask" "F.Paste")
			(net "HDD_PRSNT_NET4")
			(options
				(clearance outline)
				(anchor circle)
			)
			(primitives
				(gr_poly
					(pts
						(arc
							(start 0.3048 -0.2032)
							(mid 0.275042 -0.275042)
							(end 0.2032 -0.3048)
						)
						(arc
							(start -0.2032 -0.3048)
							(mid -0.275042 -0.275042)
							(end -0.3048 -0.2032)
						)
						(arc
							(start -0.3048 0.2032)
							(mid -0.275042 0.275042)
							(end -0.2032 0.3048)
						)
						(arc
							(start 0.2032 0.3048)
							(mid 0.275042 0.275042)
							(end 0.3048 0.2032)
						)
					)
					(width 0)
					(fill yes)
				)
			)
		)
		(pad "2" smd custom
			(at 0 0.4445)
			(size 0.1524 0.1524)
			(layers "F.Cu" "F.Mask" "F.Paste")
			(net "GND")
			(options
				(clearance outline)
				(anchor circle)
			)
			(primitives
				(gr_poly
					(pts
						(arc
							(start 0.3048 -0.2032)
							(mid 0.275042 -0.275042)
							(end 0.2032 -0.3048)
						)
						(arc
							(start -0.2032 -0.3048)
							(mid -0.275042 -0.275042)
							(end -0.3048 -0.2032)
						)
						(arc
							(start -0.3048 0.2032)
							(mid -0.275042 0.275042)
							(end -0.2032 0.3048)
						)
						(arc
							(start 0.2032 0.3048)
							(mid 0.275042 0.275042)
							(end 0.3048 0.2032)
						)
					)
					(width 0)
					(fill yes)
				)
			)
		)
	)
	(footprint ""
		(layer "F.Cu")
		(at 57.356756 -489.105702 180)
		(property "Reference" "C189"
			(at 0 0 180)
			(layer "F.SilkS")
			(hide yes)
			(effects
				(font
					(size 1.27 1.27)
				)
			)
		)
		(property "Value" "SC10U16V6KX-2GP"
			(at -0.0762 -5.1308 180)
			(unlocked yes)
			(layer "F.Fab")
			(hide yes)
			(effects
				(font
					(size 1.016 1.016)
					(thickness 0.1524)
				)
			)
		)
		(property "Device Type" "C1206H71"
			(at -0.127 -6.6548 180)
			(unlocked yes)
			(layer "F.Fab")
			(hide yes)
			(effects
				(font
					(size 1.016 1.016)
					(thickness 0.1524)
				)
			)
		)
		(duplicate_pad_numbers_are_jumpers no)
		(fp_line
			(start 1.016 2.2352)
			(end -1.016 2.2352)
			(stroke
				(width 0.1524)
				(type default)
			)
			(layer "F.SilkS")
		)
		(fp_line
			(start 1.016 0.8382)
			(end 1.016 2.2352)
			(stroke
				(width 0.1524)
				(type default)
			)
			(layer "F.SilkS")
		)
		(fp_line
			(start 1.016 -2.2352)
			(end 1.016 -0.8382)
			(stroke
				(width 0.1524)
				(type default)
			)
			(layer "F.SilkS")
		)
		(fp_line
			(start -1.016 2.2352)
			(end -1.016 0.8382)
			(stroke
				(width 0.1524)
				(type default)
			)
			(layer "F.SilkS")
		)
		(fp_line
			(start -1.016 -0.8382)
			(end -1.016 -2.2352)
			(stroke
				(width 0.1524)
				(type default)
			)
			(layer "F.SilkS")
		)
		(fp_line
			(start -1.016 -2.2352)
			(end 1.016 -2.2352)
			(stroke
				(width 0.1524)
				(type default)
			)
			(layer "F.SilkS")
		)
		(fp_rect
			(start -1.0922 2.3114)
			(end 1.0922 -2.3114)
			(stroke
				(width 0)
				(type default)
			)
			(fill no)
			(layer "F.CrtYd")
		)
		(fp_poly
			(pts
				(xy 1.0922 -2.3114) (xy 1.0922 2.3114) (xy -1.0922 2.3114) (xy -1.0922 -2.3114)
			)
			(stroke
				(width 0)
				(type default)
			)
			(fill no)
			(layer "F.Fab")
		)
		(pad "1" smd rect
			(at 0 -1.397 180)
			(size 1.651 1.27)
			(layers "F.Cu" "F.Mask" "F.Paste")
			(net "P5V_HDD5")
		)
		(pad "2" smd rect
			(at 0 1.397 180)
			(size 1.651 1.27)
			(layers "F.Cu" "F.Mask" "F.Paste")
			(net "GND")
		)
	)
	(footprint ""
		(layer "F.Cu")
		(at 43.179746 -29.9847 180)
		(property "Reference" "PC26"
			(at 0 0 180)
			(layer "F.SilkS")
			(hide yes)
			(effects
				(font
					(size 1.27 1.27)
				)
			)
		)
		(property "Value" "SC10U16V6KX-2GP"
			(at -0.0762 -5.1308 180)
			(unlocked yes)
			(layer "F.Fab")
			(hide yes)
			(effects
				(font
					(size 1.016 1.016)
					(thickness 0.1524)
				)
			)
		)
		(property "Device Type" "C1206H71"
			(at -0.127 -6.6548 180)
			(unlocked yes)
			(layer "F.Fab")
			(hide yes)
			(effects
				(font
					(size 1.016 1.016)
					(thickness 0.1524)
				)
			)
		)
		(duplicate_pad_numbers_are_jumpers no)
		(fp_line
			(start 1.016 2.2352)
			(end -1.016 2.2352)
			(stroke
				(width 0.1524)
				(type default)
			)
			(layer "F.SilkS")
		)
		(fp_line
			(start 1.016 0.8382)
			(end 1.016 2.2352)
			(stroke
				(width 0.1524)
				(type default)
			)
			(layer "F.SilkS")
		)
		(fp_line
			(start 1.016 -2.2352)
			(end 1.016 -0.8382)
			(stroke
				(width 0.1524)
				(type default)
			)
			(layer "F.SilkS")
		)
		(fp_line
			(start -1.016 2.2352)
			(end -1.016 0.8382)
			(stroke
				(width 0.1524)
				(type default)
			)
			(layer "F.SilkS")
		)
		(fp_line
			(start -1.016 -0.8382)
			(end -1.016 -2.2352)
			(stroke
				(width 0.1524)
				(type default)
			)
			(layer "F.SilkS")
		)
		(fp_line
			(start -1.016 -2.2352)
			(end 1.016 -2.2352)
			(stroke
				(width 0.1524)
				(type default)
			)
			(layer "F.SilkS")
		)
		(fp_rect
			(start -1.0922 2.3114)
			(end 1.0922 -2.3114)
			(stroke
				(width 0)
				(type default)
			)
			(fill no)
			(layer "F.CrtYd")
		)
		(fp_poly
			(pts
				(xy 1.0922 -2.3114) (xy 1.0922 2.3114) (xy -1.0922 2.3114) (xy -1.0922 -2.3114)
			)
			(stroke
				(width 0)
				(type default)
			)
			(fill no)
			(layer "F.Fab")
		)
		(pad "1" smd rect
			(at 0 -1.397 180)
			(size 1.651 1.27)
			(layers "F.Cu" "F.Mask" "F.Paste")
			(net "P5VB")
		)
		(pad "2" smd rect
			(at 0 1.397 180)
			(size 1.651 1.27)
			(layers "F.Cu" "F.Mask" "F.Paste")
			(net "GND")
		)
	)
)
